# T6G (Grand Teton) — schematic netlist excerpt (pin names and nets, part order shuffled) for the footprints in the layout excerpt that follows; sources: Cadence DE-HDL packaged netlist, KiCad conversion of 04192023_DAF0TMB3IC0_F0TG_MB_C_brd_V02_OCP.brd

R377  Q_RES  15 1% CHIP  pkg 0402LF  page 12 : A = M_C_CPU0_ALERT_N ; B = M_C_CPU0_ALERT_R_N
R2212  Q_RES  2.2K 5% EMPTY  pkg 0402LF  page 151 : A = SMB_HOST_CLK_3V3AUX_SCL ; B = P3V3_AUX

(kicad_pcb
	(version 20260206)
	(generator "pcbnew")
	(generator_version "10.0")
	(general
		(thickness 1.6)
		(legacy_teardrops no)
	)
	(paper "A4")
	(title_block
		(title "04192023_DAF0TMB3IC0_F0TG_MB_C_brd_V02_OCP.brd")
		(comment 1 "Grand Teton / footprints 7975-7976 of 8354")
	)
	(layers
		(0 "F.Cu" signal "TOP")
		(4 "In1.Cu" signal "GND")
		(6 "In2.Cu" signal "IN1")
		(8 "In3.Cu" signal "GND1")
		(10 "In4.Cu" signal "IN2")
		(12 "In5.Cu" signal "GND2")
		(14 "In6.Cu" signal "IN3")
		(16 "In7.Cu" signal "GND3")
		(18 "In8.Cu" signal "VCC")
		(20 "In9.Cu" signal "VCC1")
		(22 "In10.Cu" signal "GND4")
		(24 "In11.Cu" signal "IN4")
		(26 "In12.Cu" signal "GND5")
		(28 "In13.Cu" signal "IN5")
		(30 "In14.Cu" signal "GND6")
		(32 "In15.Cu" signal "IN6")
		(34 "In16.Cu" signal "GND7")
		(2 "B.Cu" signal "BOTTOM")
		(9 "F.Adhes" user "F.Adhesive")
		(11 "B.Adhes" user "B.Adhesive")
		(13 "F.Paste" user "Package Geometry/Pastemask Top")
		(15 "B.Paste" user "Package Geometry/Pastemask Bottom")
		(5 "F.SilkS" user "Ref Des/Silkscreen Top")
		(7 "B.SilkS" user "Ref Des/Silkscreen Bottom")
		(1 "F.Mask" user "Board Geometry/Soldermask Top")
		(3 "B.Mask" user "Board Geometry/Soldermask Bottom")
		(17 "Dwgs.User" user "User.Drawings")
		(19 "Cmts.User" user "User.Comments")
		(21 "Eco1.User" user "User.Eco1")
		(23 "Eco2.User" user "User.Eco2")
		(25 "Edge.Cuts" user "Board Geometry/Outline")
		(27 "Margin" user)
		(31 "F.CrtYd" user "Package Geometry/Place Bound Top")
		(29 "B.CrtYd" user "Package Geometry/Place Bound Bottom")
		(35 "F.Fab" user "Ref Des/Assembly Top")
		(33 "B.Fab" user "Ref Des/Assembly Bottom")
	)
	(footprint ""
		(layer "B.Cu")
		(at 293.277036 -244.08511 180)
		(property "Reference" "R377"
			(at 0 0 0)
			(layer "B.SilkS")
			(hide yes)
			(effects
				(font
					(size 1.27 1.27)
				)
				(justify mirror)
			)
		)
		(property "Value" ""
			(at 0 0 0)
			(layer "B.Fab")
			(effects
				(font
					(size 1.27 1.27)
				)
				(justify mirror)
			)
		)
		(duplicate_pad_numbers_are_jumpers no)
		(fp_line
			(start 0.7874 0.4064)
			(end 0.7874 -0.4064)
			(stroke
				(width 0.1524)
				(type default)
			)
			(layer "B.SilkS")
		)
		(fp_line
			(start 0.7874 -0.4064)
			(end -0.7874 -0.4064)
			(stroke
				(width 0.1524)
				(type default)
			)
			(layer "B.SilkS")
		)
		(fp_line
			(start -0.7874 0.4064)
			(end 0.7874 0.4064)
			(stroke
				(width 0.1524)
				(type default)
			)
			(layer "B.SilkS")
		)
		(fp_line
			(start -0.7874 -0.4064)
			(end -0.7874 0.4064)
			(stroke
				(width 0.1524)
				(type default)
			)
			(layer "B.SilkS")
		)
		(fp_line
			(start 0.67945 0.3048)
			(end 0.67945 -0.305054)
			(stroke
				(width 0.1)
				(type default)
			)
			(layer "B.Fab")
		)
		(fp_line
			(start 0.67945 -0.305054)
			(end 0.12065 -0.305054)
			(stroke
				(width 0.1)
				(type default)
			)
			(layer "B.Fab")
		)
		(fp_line
			(start 0.12065 0.3048)
			(end 0.67945 0.3048)
			(stroke
				(width 0.1)
				(type default)
			)
			(layer "B.Fab")
		)
		(fp_line
			(start 0.12065 0.2794)
			(end 0.12065 0.3048)
			(stroke
				(width 0.1)
				(type default)
			)
			(layer "B.Fab")
		)
		(fp_line
			(start 0.12065 -0.2794)
			(end -0.12065 -0.2794)
			(stroke
				(width 0.1)
				(type default)
			)
			(layer "B.Fab")
		)
		(fp_line
			(start 0.12065 -0.305054)
			(end 0.12065 -0.2794)
			(stroke
				(width 0.1)
				(type default)
			)
			(layer "B.Fab")
		)
		(fp_line
			(start -0.120396 0.3048)
			(end -0.120396 0.2794)
			(stroke
				(width 0.1)
				(type default)
			)
			(layer "B.Fab")
		)
		(fp_line
			(start -0.120396 0.2794)
			(end 0.12065 0.2794)
			(stroke
				(width 0.1)
				(type default)
			)
			(layer "B.Fab")
		)
		(fp_line
			(start -0.12065 -0.2794)
			(end -0.12065 -0.3048)
			(stroke
				(width 0.1)
				(type default)
			)
			(layer "B.Fab")
		)
		(fp_line
			(start -0.12065 -0.3048)
			(end -0.67945 -0.3048)
			(stroke
				(width 0.1)
				(type default)
			)
			(layer "B.Fab")
		)
		(fp_line
			(start -0.67945 0.3048)
			(end -0.120396 0.3048)
			(stroke
				(width 0.1)
				(type default)
			)
			(layer "B.Fab")
		)
		(fp_line
			(start -0.67945 -0.3048)
			(end -0.67945 0.3048)
			(stroke
				(width 0.1)
				(type default)
			)
			(layer "B.Fab")
		)
		(pad "1" smd circle
			(at 0.40005 0)
			(size 0 0)
			(layers "B.Cu" "B.Mask" "B.Paste")
			(net "M_C_CPU0_ALERT_N")
		)
		(pad "2" smd circle
			(at -0.40005 0)
			(size 0 0)
			(layers "B.Cu" "B.Mask" "B.Paste")
			(net "M_C_CPU0_ALERT_R_N")
		)
	)
	(footprint ""
		(layer "B.Cu")
		(at 150.988776 -17.693894 -90)
		(property "Reference" "R2212"
			(at 0 0 90)
			(layer "B.SilkS")
			(hide yes)
			(effects
				(font
					(size 1.27 1.27)
				)
				(justify mirror)
			)
		)
		(property "Value" ""
			(at 0 0 90)
			(layer "B.Fab")
			(effects
				(font
					(size 1.27 1.27)
				)
				(justify mirror)
			)
		)
		(duplicate_pad_numbers_are_jumpers no)
		(fp_line
			(start -0.7874 0.4064)
			(end 0.7874 0.4064)
			(stroke
				(width 0.1524)
				(type default)
			)
			(layer "B.SilkS")
		)
		(fp_line
			(start 0.7874 0.4064)
			(end 0.7874 -0.4064)
			(stroke
				(width 0.1524)
				(type default)
			)
			(layer "B.SilkS")
		)
		(fp_line
			(start -0.7874 -0.4064)
			(end -0.7874 0.4064)
			(stroke
				(width 0.1524)
				(type default)
			)
			(layer "B.SilkS")
		)
		(fp_line
			(start 0.7874 -0.4064)
			(end -0.7874 -0.4064)
			(stroke
				(width 0.1524)
				(type default)
			)
			(layer "B.SilkS")
		)
		(fp_line
			(start -0.67945 0.3048)
			(end -0.120396 0.3048)
			(stroke
				(width 0.1)
				(type default)
			)
			(layer "B.Fab")
		)
		(fp_line
			(start -0.120396 0.3048)
			(end -0.120396 0.2794)
			(stroke
				(width 0.1)
				(type default)
			)
			(layer "B.Fab")
		)
		(fp_line
			(start 0.12065 0.3048)
			(end 0.67945 0.3048)
			(stroke
				(width 0.1)
				(type default)
			)
			(layer "B.Fab")
		)
		(fp_line
			(start 0.67945 0.3048)
			(end 0.67945 -0.305054)
			(stroke
				(width 0.1)
				(type default)
			)
			(layer "B.Fab")
		)
		(fp_line
			(start -0.120396 0.2794)
			(end 0.12065 0.2794)
			(stroke
				(width 0.1)
				(type default)
			)
			(layer "B.Fab")
		)
		(fp_line
			(start 0.12065 0.2794)
			(end 0.12065 0.3048)
			(stroke
				(width 0.1)
				(type default)
			)
			(layer "B.Fab")
		)
		(fp_line
			(start -0.12065 -0.2794)
			(end -0.12065 -0.3048)
			(stroke
				(width 0.1)
				(type default)
			)
			(layer "B.Fab")
		)
		(fp_line
			(start 0.12065 -0.2794)
			(end -0.12065 -0.2794)
			(stroke
				(width 0.1)
				(type default)
			)
			(layer "B.Fab")
		)
		(fp_line
			(start -0.67945 -0.3048)
			(end -0.67945 0.3048)
			(stroke
				(width 0.1)
				(type default)
			)
			(layer "B.Fab")
		)
		(fp_line
			(start -0.12065 -0.3048)
			(end -0.67945 -0.3048)
			(stroke
				(width 0.1)
				(type default)
			)
			(layer "B.Fab")
		)
		(fp_line
			(start 0.12065 -0.305054)
			(end 0.12065 -0.2794)
			(stroke
				(width 0.1)
				(type default)
			)
			(layer "B.Fab")
		)
		(fp_line
			(start 0.67945 -0.305054)
			(end 0.12065 -0.305054)
			(stroke
				(width 0.1)
				(type default)
			)
			(layer "B.Fab")
		)
		(pad "1" smd circle
			(at 0.40005 0 90)
			(size 0 0)
			(layers "B.Cu" "B.Mask" "B.Paste")
			(net "SMB_HOST_CLK_3V3AUX_SCL")
		)
		(pad "2" smd circle
			(at -0.40005 0 90)
			(size 0 0)
			(layers "B.Cu" "B.Mask" "B.Paste")
			(net "P3V3_AUX")
		)
	)
)
